(kicad_pcb
	(version 20260206)
	(generator "pcbnew")
	(generator_version "10.0")
	(general
		(thickness 1.6)
		(legacy_teardrops no)
	)
	(paper "A4")
	(title_block
		(title "Wiwynn_Tioga_Pass_MB.brd")
		(comment 1 "Tioga Pass / footprints 118-124 of 4770")
	)
	(layers
		(0 "F.Cu" signal "TOP")
		(4 "In1.Cu" signal "L2GND")
		(6 "In2.Cu" signal "L3")
		(8 "In3.Cu" signal "L4GND")
		(10 "In4.Cu" signal "L5")
		(12 "In5.Cu" signal "L6GND")
		(14 "In6.Cu" signal "L7VCC")
		(16 "In7.Cu" signal "L8VCC")
		(18 "In8.Cu" signal "L9GND")
		(20 "In9.Cu" signal "L10")
		(22 "In10.Cu" signal "L11GND")
		(24 "In11.Cu" signal "L12")
		(26 "In12.Cu" signal "L13GND")
		(2 "B.Cu" signal "BOTTOM")
		(9 "F.Adhes" user "F.Adhesive")
		(11 "B.Adhes" user "B.Adhesive")
		(13 "F.Paste" user "Package Geometry/Pastemask Top")
		(15 "B.Paste" user "Package Geometry/Pastemask Bottom")
		(5 "F.SilkS" user "Ref Des/Silkscreen Top")
		(7 "B.SilkS" user "Ref Des/Silkscreen Bottom")
		(1 "F.Mask" user "Board Geometry/Soldermask Top")
		(3 "B.Mask" user "Board Geometry/Soldermask Bottom")
		(17 "Dwgs.User" user "User.Drawings")
		(19 "Cmts.User" user "User.Comments")
		(21 "Eco1.User" user "User.Eco1")
		(23 "Eco2.User" user "User.Eco2")
		(25 "Edge.Cuts" user "Board Geometry/Outline")
		(27 "Margin" user)
		(31 "F.CrtYd" user "Package Geometry/Place Bound Top")
		(29 "B.CrtYd" user "Package Geometry/Place Bound Bottom")
		(35 "F.Fab" user "Ref Des/Assembly Top")
		(33 "B.Fab" user "Ref Des/Assembly Bottom")
	)
	(footprint ""
		(layer "F.Cu")
		(at 33.178496 -77.605382 90)
		(property "Reference" "C1D6"
			(at 0 0 90)
			(layer "F.SilkS")
			(hide yes)
			(effects
				(font
					(size 1.27 1.27)
				)
			)
		)
		(property "Value" ""
			(at 0 0 90)
			(layer "F.Fab")
			(effects
				(font
					(size 1.27 1.27)
				)
			)
		)
		(duplicate_pad_numbers_are_jumpers no)
		(fp_rect
			(start 0.3048 0.9906)
			(end -0.3048 -0.1016)
			(stroke
				(width 0)
				(type default)
			)
			(fill no)
			(layer "F.CrtYd")
		)
		(fp_line
			(start 0.3048 -0.1016)
			(end -0.3048 -0.1016)
			(stroke
				(width 0.1)
				(type default)
			)
			(layer "F.Fab")
		)
		(fp_line
			(start -0.3048 -0.1016)
			(end -0.3048 0.9906)
			(stroke
				(width 0.1)
				(type default)
			)
			(layer "F.Fab")
		)
		(fp_line
			(start 0.3048 0.9906)
			(end 0.3048 -0.1016)
			(stroke
				(width 0.1)
				(type default)
			)
			(layer "F.Fab")
		)
		(fp_line
			(start -0.3048 0.9906)
			(end 0.3048 0.9906)
			(stroke
				(width 0.1)
				(type default)
			)
			(layer "F.Fab")
		)
		(pad "1" smd rect
			(at 0 0 90)
			(size 0.508 0.508)
			(layers "F.Cu" "F.Mask" "F.Paste")
			(net "P5V_STBY")
		)
		(pad "2" smd rect
			(at 0 0.889 90)
			(size 0.508 0.508)
			(layers "F.Cu" "F.Mask" "F.Paste")
			(net "GND")
		)
		(zone
			(layer "F.Cu")
			(hatch none 0.5)
			(connect_pads
				(clearance 0)
			)
			(min_thickness 0.25)
			(keepout
				(tracks not_allowed)
				(vias allowed)
				(pads allowed)
				(copperpour not_allowed)
				(footprints allowed)
			)
			(placement
				(enabled no)
				(sheetname "")
			)
			(fill
				(thermal_gap 0.5)
				(thermal_bridge_width 0.5)
				(island_removal_mode 0)
			)
			(polygon
				(pts
					(xy 33.813496 -77.859382) (xy 33.432496 -77.859382) (xy 33.432496 -77.351382) (xy 33.813496 -77.351382)
				)
			)
		)
		(zone
			(layer "F.Cu")
			(hatch none 0.5)
			(connect_pads
				(clearance 0)
			)
			(min_thickness 0.25)
			(keepout
				(tracks allowed)
				(vias not_allowed)
				(pads allowed)
				(copperpour not_allowed)
				(footprints allowed)
			)
			(placement
				(enabled no)
				(sheetname "")
			)
			(fill
				(thermal_gap 0.5)
				(thermal_bridge_width 0.5)
				(island_removal_mode 0)
			)
			(polygon
				(pts
					(xy 33.813496 -77.859382) (xy 33.432496 -77.859382) (xy 33.432496 -77.351382) (xy 33.813496 -77.351382)
				)
			)
		)
	)
	(footprint ""
		(layer "F.Cu")
		(at 14.732 -88.4936 -90)
		(property "Reference" "R1C30"
			(at 0 0 270)
			(layer "F.SilkS")
			(hide yes)
			(effects
				(font
					(size 1.27 1.27)
				)
			)
		)
		(property "Value" ""
			(at 0 0 270)
			(layer "F.Fab")
			(effects
				(font
					(size 1.27 1.27)
				)
			)
		)
		(duplicate_pad_numbers_are_jumpers no)
		(fp_rect
			(start 0.2794 0.9906)
			(end -0.2794 -0.1016)
			(stroke
				(width 0)
				(type default)
			)
			(fill no)
			(layer "F.CrtYd")
		)
		(fp_line
			(start -0.2794 0.9906)
			(end 0.2794 0.9906)
			(stroke
				(width 0.1)
				(type default)
			)
			(layer "F.Fab")
		)
		(fp_line
			(start 0.2794 0.9906)
			(end 0.2794 -0.1016)
			(stroke
				(width 0.1)
				(type default)
			)
			(layer "F.Fab")
		)
		(fp_line
			(start -0.2794 -0.1016)
			(end -0.2794 0.9906)
			(stroke
				(width 0.1)
				(type default)
			)
			(layer "F.Fab")
		)
		(fp_line
			(start 0.2794 -0.1016)
			(end -0.2794 -0.1016)
			(stroke
				(width 0.1)
				(type default)
			)
			(layer "F.Fab")
		)
		(pad "1" smd rect
			(at 0 0 270)
			(size 0.508 0.508)
			(layers "F.Cu" "F.Mask" "F.Paste")
			(net "VR_VRRDY_PVCCIN_CPU1")
		)
		(pad "2" smd rect
			(at 0 0.889 270)
			(size 0.508 0.508)
			(layers "F.Cu" "F.Mask" "F.Paste")
			(net "PWRGD_PVCCIN_CPU1")
		)
		(zone
			(layer "F.Cu")
			(hatch none 0.5)
			(connect_pads
				(clearance 0)
			)
			(min_thickness 0.25)
			(keepout
				(tracks not_allowed)
				(vias allowed)
				(pads allowed)
				(copperpour not_allowed)
				(footprints allowed)
			)
			(placement
				(enabled no)
				(sheetname "")
			)
			(fill
				(thermal_gap 0.5)
				(thermal_bridge_width 0.5)
				(island_removal_mode 0)
			)
			(polygon
				(pts
					(xy 14.097 -88.2396) (xy 14.478 -88.2396) (xy 14.478 -88.7476) (xy 14.097 -88.7476)
				)
			)
		)
		(zone
			(layer "F.Cu")
			(hatch none 0.5)
			(connect_pads
				(clearance 0)
			)
			(min_thickness 0.25)
			(keepout
				(tracks allowed)
				(vias not_allowed)
				(pads allowed)
				(copperpour not_allowed)
				(footprints allowed)
			)
			(placement
				(enabled no)
				(sheetname "")
			)
			(fill
				(thermal_gap 0.5)
				(thermal_bridge_width 0.5)
				(island_removal_mode 0)
			)
			(polygon
				(pts
					(xy 14.097 -88.2396) (xy 14.478 -88.2396) (xy 14.478 -88.7476) (xy 14.097 -88.7476)
				)
			)
		)
	)
	(footprint ""
		(layer "F.Cu")
		(at 3.4798 -64.77 -90)
		(property "Reference" "VR1D1"
			(at -4.06273 5.6896 0)
			(unlocked yes)
			(layer "F.SilkS")
			(effects
				(font
					(size 0.7874 0.5842)
					(thickness 0.1524)
				)
				(justify left)
			)
		)
		(property "Value" ""
			(at 0 0 270)
			(layer "F.Fab")
			(effects
				(font
					(size 1.27 1.27)
				)
			)
		)
		(duplicate_pad_numbers_are_jumpers no)
		(fp_line
			(start -3.1115 7.5946)
			(end -1.9431 7.5946)
			(stroke
				(width 0.1524)
				(type default)
			)
			(layer "F.SilkS")
		)
		(fp_line
			(start -3.1115 7.5946)
			(end -3.1115 -0.2286)
			(stroke
				(width 0.1524)
				(type default)
			)
			(layer "F.SilkS")
		)
		(fp_line
			(start 1.9431 7.5946)
			(end 3.1115 7.5946)
			(stroke
				(width 0.1524)
				(type default)
			)
			(layer "F.SilkS")
		)
		(fp_line
			(start -3.1115 -0.2286)
			(end -1.9431 -0.2286)
			(stroke
				(width 0.1524)
				(type default)
			)
			(layer "F.SilkS")
		)
		(fp_line
			(start 1.9431 -0.2286)
			(end 3.1115 -0.2286)
			(stroke
				(width 0.1524)
				(type default)
			)
			(layer "F.SilkS")
		)
		(fp_line
			(start 3.1115 -0.2286)
			(end 3.1115 7.5946)
			(stroke
				(width 0.1524)
				(type default)
			)
			(layer "F.SilkS")
		)
		(fp_circle
			(center -2.065528 -0.818388)
			(end -2.065528 -0.945388)
			(stroke
				(width 0.254)
				(type default)
			)
			(fill no)
			(layer "F.SilkS")
		)
		(fp_poly
			(pts
				(xy -3.1115 7.5946) (xy 3.1115 7.5946) (xy 3.1115 -0.2286) (xy -3.1115 -0.2286)
			)
			(stroke
				(width 0)
				(type default)
			)
			(fill no)
			(layer "F.CrtYd")
		)
		(fp_line
			(start -3.1115 7.5946)
			(end 3.1115 7.5946)
			(stroke
				(width 0.1)
				(type default)
			)
			(layer "F.Fab")
		)
		(fp_line
			(start 3.1115 7.5946)
			(end 3.1115 -0.2286)
			(stroke
				(width 0.1)
				(type default)
			)
			(layer "F.Fab")
		)
		(fp_line
			(start -3.1115 -0.2286)
			(end -3.1115 7.5946)
			(stroke
				(width 0.1)
				(type default)
			)
			(layer "F.Fab")
		)
		(fp_line
			(start 3.1115 -0.2286)
			(end -3.1115 -0.2286)
			(stroke
				(width 0.1)
				(type default)
			)
			(layer "F.Fab")
		)
		(fp_circle
			(center -2.413 -0.9906)
			(end -2.413 -1.1176)
			(stroke
				(width 0.254)
				(type default)
			)
			(fill no)
			(layer "F.Fab")
		)
		(pad "1" smd rect
			(at 0 0 270)
			(size 3.048 2.286)
			(layers "F.Cu" "F.Mask" "F.Paste")
			(net "P12V_PSU")
		)
		(pad "2" smd rect
			(at 0 7.366 270)
			(size 3.048 2.286)
			(layers "F.Cu" "F.Mask" "F.Paste")
			(net "GND")
		)
	)
	(footprint ""
		(layer "F.Cu")
		(at 381.51562 -150.965916 180)
		(property "Reference" "RT45"
			(at 0 0 180)
			(layer "F.SilkS")
			(hide yes)
			(effects
				(font
					(size 1.27 1.27)
				)
			)
		)
		(property "Value" "*"
			(at -0.0254 -2.6289 180)
			(unlocked yes)
			(layer "F.Fab")
			(hide yes)
			(effects
				(font
					(size 1.27 1.016)
					(thickness 0.1524)
				)
			)
		)
		(property "Device Type" "1R3F-GP_RCL_GP-1R3F-GP,64.1R00A"
			(at -0.0254 -4.1529 180)
			(unlocked yes)
			(layer "F.Fab")
			(hide yes)
			(effects
				(font
					(size 1.27 1.016)
					(thickness 0.1524)
				)
			)
		)
		(duplicate_pad_numbers_are_jumpers no)
		(fp_line
			(start 0.2032 0)
			(end 0.4826 0)
			(stroke
				(width 0.2032)
				(type default)
			)
			(layer "F.SilkS")
		)
		(fp_line
			(start -0.4826 0)
			(end -0.2032 0)
			(stroke
				(width 0.2032)
				(type default)
			)
			(layer "F.SilkS")
		)
		(fp_poly
			(pts
				(xy -0.5842 1.3335) (xy 0.5842 1.3335) (xy 0.5842 -1.3335) (xy -0.5842 -1.3335)
			)
			(stroke
				(width 0)
				(type default)
			)
			(fill no)
			(layer "F.CrtYd")
		)
		(fp_rect
			(start -0.5842 1.3335)
			(end 0.5842 -1.3335)
			(stroke
				(width 0)
				(type default)
			)
			(fill no)
			(layer "F.Fab")
		)
		(pad "1" smd custom
			(at 0 -0.762 180)
			(size 0.2159 0.2159)
			(layers "F.Cu" "F.Mask" "F.Paste")
			(net "VR_P1V05_PCH_STBY_PH1_SW_RC")
			(options
				(clearance outline)
				(anchor circle)
			)
			(primitives
				(gr_poly
					(pts
						(arc
							(start -0.3302 -0.4318)
							(mid -0.402042 -0.402042)
							(end -0.4318 -0.3302)
						)
						(arc
							(start -0.4318 0.3302)
							(mid -0.402042 0.402042)
							(end -0.3302 0.4318)
						)
						(arc
							(start 0.3302 0.4318)
							(mid 0.402042 0.402042)
							(end 0.4318 0.3302)
						)
						(arc
							(start 0.4318 -0.3302)
							(mid 0.402042 -0.402042)
							(end 0.3302 -0.4318)
						)
					)
					(width 0)
					(fill yes)
				)
			)
		)
		(pad "2" smd custom
			(at 0 0.762 180)
			(size 0.2159 0.2159)
			(layers "F.Cu" "F.Mask" "F.Paste")
			(net "GND")
			(options
				(clearance outline)
				(anchor circle)
			)
			(primitives
				(gr_poly
					(pts
						(arc
							(start -0.3302 -0.4318)
							(mid -0.402042 -0.402042)
							(end -0.4318 -0.3302)
						)
						(arc
							(start -0.4318 0.3302)
							(mid -0.402042 0.402042)
							(end -0.3302 0.4318)
						)
						(arc
							(start 0.3302 0.4318)
							(mid 0.402042 0.402042)
							(end 0.4318 0.3302)
						)
						(arc
							(start 0.4318 -0.3302)
							(mid 0.402042 -0.402042)
							(end 0.3302 -0.4318)
						)
					)
					(width 0)
					(fill yes)
				)
			)
		)
	)
	(footprint ""
		(layer "F.Cu")
		(at 162.687 -104.14)
		(property "Reference" "C3C2"
			(at 0 0 0)
			(layer "F.SilkS")
			(hide yes)
			(effects
				(font
					(size 1.27 1.27)
				)
			)
		)
		(property "Value" ""
			(at 0 0 0)
			(layer "F.Fab")
			(effects
				(font
					(size 1.27 1.27)
				)
			)
		)
		(duplicate_pad_numbers_are_jumpers no)
		(fp_poly
			(pts
				(xy 0.3048 -0.1016) (xy 0.3048 0.9906) (xy -0.3048 0.9906) (xy -0.3048 -0.1016)
			)
			(stroke
				(width 0)
				(type default)
			)
			(fill no)
			(layer "F.CrtYd")
		)
		(fp_line
			(start -0.3048 -0.1016)
			(end -0.3048 0.9906)
			(stroke
				(width 0.1)
				(type default)
			)
			(layer "F.Fab")
		)
		(fp_line
			(start -0.3048 0.9906)
			(end 0.3048 0.9906)
			(stroke
				(width 0.1)
				(type default)
			)
			(layer "F.Fab")
		)
		(fp_line
			(start 0.3048 -0.1016)
			(end -0.3048 -0.1016)
			(stroke
				(width 0.1)
				(type default)
			)
			(layer "F.Fab")
		)
		(fp_line
			(start 0.3048 0.9906)
			(end 0.3048 -0.1016)
			(stroke
				(width 0.1)
				(type default)
			)
			(layer "F.Fab")
		)
		(pad "1" smd rect
			(at 0 0)
			(size 0.508 0.508)
			(layers "F.Cu" "F.Mask" "F.Paste")
			(net "PVCCIOMCP_CPU1")
		)
		(pad "2" smd rect
			(at 0 0.889)
			(size 0.508 0.508)
			(layers "F.Cu" "F.Mask" "F.Paste")
			(net "GND")
		)
		(zone
			(layer "F.Cu")
			(hatch none 0.5)
			(connect_pads
				(clearance 0)
			)
			(min_thickness 0.25)
			(keepout
				(tracks allowed)
				(vias not_allowed)
				(pads allowed)
				(copperpour not_allowed)
				(footprints allowed)
			)
			(placement
				(enabled no)
				(sheetname "")
			)
			(fill
				(thermal_gap 0.5)
				(thermal_bridge_width 0.5)
				(island_removal_mode 0)
			)
			(polygon
				(pts
					(xy 162.433 -103.886) (xy 162.941 -103.886) (xy 162.941 -103.505) (xy 162.433 -103.505)
				)
			)
		)
		(zone
			(layer "F.Cu")
			(hatch none 0.5)
			(connect_pads
				(clearance 0)
			)
			(min_thickness 0.25)
			(keepout
				(tracks not_allowed)
				(vias allowed)
				(pads allowed)
				(copperpour not_allowed)
				(footprints allowed)
			)
			(placement
				(enabled no)
				(sheetname "")
			)
			(fill
				(thermal_gap 0.5)
				(thermal_bridge_width 0.5)
				(island_removal_mode 0)
			)
			(polygon
				(pts
					(xy 162.433 -103.505) (xy 162.941 -103.505) (xy 162.941 -103.886) (xy 162.433 -103.886)
				)
			)
		)
	)
	(footprint ""
		(layer "F.Cu")
		(at 88.392 -3.3528 90)
		(property "Reference" "C2G12"
			(at 1.848866 0.752348 90)
			(unlocked yes)
			(layer "F.SilkS")
			(effects
				(font
					(size 1.27 0.9652)
					(thickness 0.1524)
				)
			)
		)
		(property "Value" ""
			(at 0 0 90)
			(layer "F.Fab")
			(effects
				(font
					(size 1.27 1.27)
				)
			)
		)
		(duplicate_pad_numbers_are_jumpers no)
		(fp_rect
			(start -0.500126 1.598422)
			(end 0.500126 -0.201422)
			(stroke
				(width 0)
				(type default)
			)
			(fill no)
			(layer "F.CrtYd")
		)
		(fp_line
			(start 0.500126 -0.201422)
			(end 0.500126 1.598422)
			(stroke
				(width 0.1)
				(type default)
			)
			(layer "F.Fab")
		)
		(fp_line
			(start -0.500126 -0.201422)
			(end 0.500126 -0.201422)
			(stroke
				(width 0.1)
				(type default)
			)
			(layer "F.Fab")
		)
		(fp_line
			(start 0.500126 1.598422)
			(end -0.500126 1.598422)
			(stroke
				(width 0.1)
				(type default)
			)
			(layer "F.Fab")
		)
		(fp_line
			(start -0.500126 1.598422)
			(end -0.500126 -0.201422)
			(stroke
				(width 0.1)
				(type default)
			)
			(layer "F.Fab")
		)
		(pad "1" smd rect
			(at 0 0)
			(size 0.889 0.9906)
			(layers "F.Cu" "F.Mask" "F.Paste")
			(net "PVDDQ_GHJ")
		)
		(pad "2" smd rect
			(at 0 1.397)
			(size 0.889 0.9906)
			(layers "F.Cu" "F.Mask" "F.Paste")
			(net "GND")
		)
		(zone
			(layer "F.Cu")
			(hatch none 0.5)
			(connect_pads
				(clearance 0)
			)
			(min_thickness 0.25)
			(keepout
				(tracks allowed)
				(vias not_allowed)
				(pads allowed)
				(copperpour not_allowed)
				(footprints allowed)
			)
			(placement
				(enabled no)
				(sheetname "")
			)
			(fill
				(thermal_gap 0.5)
				(thermal_bridge_width 0.5)
				(island_removal_mode 0)
			)
			(polygon
				(pts
					(xy 89.3445 -2.8575) (xy 89.3445 -3.8481) (xy 88.8365 -3.8481) (xy 88.8365 -2.8575)
				)
			)
		)
		(zone
			(layer "F.Cu")
			(hatch none 0.5)
			(connect_pads
				(clearance 0)
			)
			(min_thickness 0.25)
			(keepout
				(tracks not_allowed)
				(vias allowed)
				(pads allowed)
				(copperpour not_allowed)
				(footprints allowed)
			)
			(placement
				(enabled no)
				(sheetname "")
			)
			(fill
				(thermal_gap 0.5)
				(thermal_bridge_width 0.5)
				(island_removal_mode 0)
			)
			(polygon
				(pts
					(xy 89.3445 -2.8575) (xy 89.3445 -3.8481) (xy 88.8365 -3.8481) (xy 88.8365 -2.8575)
				)
			)
		)
	)
	(footprint ""
		(layer "F.Cu")
		(at 178.98237 -144.159224 90)
		(property "Reference" "R4A9"
			(at 0 0 90)
			(layer "F.SilkS")
			(hide yes)
			(effects
				(font
					(size 1.27 1.27)
				)
			)
		)
		(property "Value" ""
			(at 0 0 90)
			(layer "F.Fab")
			(effects
				(font
					(size 1.27 1.27)
				)
			)
		)
		(duplicate_pad_numbers_are_jumpers no)
		(fp_poly
			(pts
				(xy -0.2794 -0.1016) (xy 0.2794 -0.1016) (xy 0.2794 0.9906) (xy -0.2794 0.9906)
			)
			(stroke
				(width 0)
				(type default)
			)
			(fill no)
			(layer "F.CrtYd")
		)
		(fp_line
			(start 0.2794 -0.1016)
			(end -0.2794 -0.1016)
			(stroke
				(width 0.1)
				(type default)
			)
			(layer "F.Fab")
		)
		(fp_line
			(start -0.2794 -0.1016)
			(end -0.2794 0.9906)
			(stroke
				(width 0.1)
				(type default)
			)
			(layer "F.Fab")
		)
		(fp_line
			(start 0.2794 0.9906)
			(end 0.2794 -0.1016)
			(stroke
				(width 0.1)
				(type default)
			)
			(layer "F.Fab")
		)
		(fp_line
			(start -0.2794 0.9906)
			(end 0.2794 0.9906)
			(stroke
				(width 0.1)
				(type default)
			)
			(layer "F.Fab")
		)
		(pad "1" smd rect
			(at 0 0 90)
			(size 0.508 0.508)
			(layers "F.Cu" "F.Mask" "F.Paste")
			(net "SMB_LAN_STBY_LVC3_SCL")
		)
		(pad "2" smd rect
			(at 0 0.889 90)
			(size 0.508 0.508)
			(layers "F.Cu" "F.Mask" "F.Paste")
			(net "SMB_PIROM_CPU0_SCL")
		)
		(zone
			(layer "F.Cu")
			(hatch none 0.5)
			(connect_pads
				(clearance 0)
			)
			(min_thickness 0.25)
			(keepout
				(tracks allowed)
				(vias not_allowed)
				(pads allowed)
				(copperpour not_allowed)
				(footprints allowed)
			)
			(placement
				(enabled no)
				(sheetname "")
			)
			(fill
				(thermal_gap 0.5)
				(thermal_bridge_width 0.5)
				(island_removal_mode 0)
			)
			(polygon
				(pts
					(xy 179.23637 -143.905224) (xy 179.23637 -144.413224) (xy 179.61737 -144.413224) (xy 179.61737 -143.905224)
				)
			)
		)
		(zone
			(layer "F.Cu")
			(hatch none 0.5)
			(connect_pads
				(clearance 0)
			)
			(min_thickness 0.25)
			(keepout
				(tracks not_allowed)
				(vias allowed)
				(pads allowed)
				(copperpour not_allowed)
				(footprints allowed)
			)
			(placement
				(enabled no)
				(sheetname "")
			)
			(fill
				(thermal_gap 0.5)
				(thermal_bridge_width 0.5)
				(island_removal_mode 0)
			)
			(polygon
				(pts
					(xy 179.61737 -143.905224) (xy 179.61737 -144.413224) (xy 179.23637 -144.413224) (xy 179.23637 -143.905224)
				)
			)
		)
	)
)
